(kicad_pcb
	(version 20221018)
	(generator pcbnew)
	(general
    (thickness 1.7403)
  )
	(paper "A4")
	(title_block
    (title "Data Center RDIMM DDR4 Tester")
    (date "2024-09-30")
    (rev "1.2.4")
		(comment 9 "footprints 688-690 of 690")
	)
	(layers
    (0 "F.Cu" signal)
    (1 "In1.Cu" power)
    (2 "In2.Cu" signal)
    (3 "In3.Cu" power)
    (4 "In4.Cu" power)
    (5 "In5.Cu" signal)
    (6 "In6.Cu" power)
    (7 "In7.Cu" signal)
    (8 "In8.Cu" power)
    (9 "In9.Cu" signal)
    (10 "In10.Cu" power)
    (31 "B.Cu" signal)
    (32 "B.Adhes" user "B.Adhesive")
    (33 "F.Adhes" user "F.Adhesive")
    (34 "B.Paste" user)
    (35 "F.Paste" user)
    (36 "B.SilkS" user "B.Silkscreen")
    (37 "F.SilkS" user "F.Silkscreen")
    (38 "B.Mask" user)
    (39 "F.Mask" user)
    (40 "Dwgs.User" user "User.Drawings")
    (41 "Cmts.User" user "User.Comments")
    (42 "Eco1.User" user "User.Eco1")
    (43 "Eco2.User" user "User.Eco2")
    (44 "Edge.Cuts" user)
    (45 "Margin" user)
    (46 "B.CrtYd" user "B.Courtyard")
    (47 "F.CrtYd" user "F.Courtyard")
    (48 "B.Fab" user)
    (49 "F.Fab" user)
  )
	(footprint "data-center-rdimm-ddr4-tester-footprints:C_0201" (layer "B.Cu")
    (at 192.2 90.54 90)
    (descr "Capacitor SMD 0201")
    (tags "capacitor SMD 0201")
    (property "Author" "Antmicro")
    (property "Dielectric" "")
    (property "License" "Apache-2.0")
    (property "MPN" "CC0201KRX6S5BB104")
    (property "Manufacturer" "Yaego")
    (property "Sheetfile" "fpga-power.kicad_sch")
    (property "Sheetname" "FPGA power")
    (property "Val" "100n")
    (property "Voltage" "")
    (property "ki_description" " ")
    (attr smd)
    (fp_text reference "C238" (at 1.17 -0.47 270) (layer "B.SilkS")
        (effects (font (size 0.7 0.7) (thickness 0.15)) (justify left bottom mirror))
    )
    (fp_text value "C_100n_0201" (at 0 -1.4 270) (layer "B.Fab") hide
        (effects (font (size 0.7 0.7) (thickness 0.15)) (justify left bottom mirror))
    )
    (fp_text user "Author: Antmicro" (at -0.72 -5.4 270) (layer "B.Fab") hide
        (effects (font (size 0.7 0.7) (thickness 0.15)) (justify left bottom mirror))
    )
    (fp_text user "License: Apache-2.0" (at -0.72 -4.4 270) (layer "B.Fab") hide
        (effects (font (size 0.7 0.7) (thickness 0.15)) (justify left bottom mirror))
    )
    (fp_text user "${REFERENCE}" (at -0.72 -3.4 270) (layer "B.Fab") hide
        (effects (font (size 0.7 0.7) (thickness 0.15)) (justify left bottom mirror))
    )
    (fp_rect (start -0.72 0.38) (end 0.72 -0.38)
      (stroke (width 0.05) (type solid)) (fill none) (layer "B.CrtYd"))
    (fp_rect (start 0.3 -0.15) (end -0.301 0.149)
      (stroke (width 0.15) (type solid)) (fill none) (layer "B.Fab"))
    (pad "" smd roundrect (at -0.349 0.002 90) (size 0.318 0.36) (layers "B.Paste") (roundrect_rratio 0.25))
    (pad "" smd roundrect (at 0.341 0.002 90) (size 0.318 0.36) (layers "B.Paste") (roundrect_rratio 0.25))
    (pad "1" smd roundrect (at -0.321 0.002 90) (size 0.46 0.4) (layers "B.Cu" "B.Mask") (roundrect_rratio 0.25)
      (net 144 "1V8_SYS") (pintype "passive"))
    (pad "2" smd roundrect (at 0.32 0.002 90) (size 0.46 0.4) (layers "B.Cu" "B.Mask") (roundrect_rratio 0.25)
      (net 9 "GND") (pintype "passive"))
  )
	(footprint "data-center-rdimm-ddr4-tester-footprints:R_0402_1005Metric" (layer "B.Cu")
    (at 171.9 76.2 180)
    (descr "Resistor SMD 0402")
    (tags "resistor SMD 0402")
    (property "Author" "Antmicro")
    (property "License" "Apache-2.0")
    (property "MPN" "CR0402-FX-1003GLF")
    (property "Manufacturer" "Bourns")
    (property "Sheetfile" "DDR4.kicad_sch")
    (property "Sheetname" "DDR4")
    (property "Tolerance" "1%")
    (property "Val" "100k")
    (property "ki_description" "100k resistor in 0402 package with 1% tolerance")
    (attr smd)
    (fp_text reference "R186" (at -1.45 0.55) (layer "B.SilkS")
        (effects (font (size 0.7 0.7) (thickness 0.15)) (justify left bottom mirror))
    )
    (fp_text value "R_100k_0402" (at 0 -1.4) (layer "B.Fab") hide
        (effects (font (size 0.7 0.7) (thickness 0.15)) (justify left bottom mirror))
    )
    (fp_text user "License: Apache-2.0" (at -0.95 -5.169) (layer "B.Fab") hide
        (effects (font (size 0.7 0.7) (thickness 0.15)) (justify left bottom mirror))
    )
    (fp_text user "${REFERENCE}" (at -0.95 -3.168) (layer "B.Fab") hide
        (effects (font (size 0.7 0.7) (thickness 0.15)) (justify left bottom mirror))
    )
    (fp_text user "Author: Antmicro" (at -0.95 -4.169) (layer "B.Fab") hide
        (effects (font (size 0.7 0.7) (thickness 0.15)) (justify left bottom mirror))
    )
    (fp_rect (start -0.93 0.47) (end 0.93 -0.47)
      (stroke (width 0.05) (type solid)) (fill none) (layer "B.CrtYd"))
    (fp_rect (start -0.5 0.25) (end 0.5 -0.25)
      (stroke (width 0.15) (type solid)) (fill none) (layer "B.Fab"))
    (pad "1" smd roundrect (at -0.485 0 180) (size 0.59 0.64) (layers "B.Cu" "B.Paste" "B.Mask") (roundrect_rratio 0.25)
      (net 789 "DDR_PRESENCE") (pintype "passive"))
    (pad "2" smd roundrect (at 0.485 0 180) (size 0.59 0.64) (layers "B.Cu" "B.Paste" "B.Mask") (roundrect_rratio 0.25)
      (net 143 "3V3_SYS") (pintype "passive"))
  )
	(footprint "data-center-rdimm-ddr4-tester-footprints:C_0201" (layer "B.Cu")
    (at 172.2 88.65)
    (descr "Capacitor SMD 0201")
    (tags "capacitor SMD 0201")
    (property "Author" "Antmicro")
    (property "Dielectric" "")
    (property "License" "Apache-2.0")
    (property "MPN" "CC0201KRX6S5BB104")
    (property "Manufacturer" "Yaego")
    (property "Sheetfile" "fpga-power.kicad_sch")
    (property "Sheetname" "FPGA power")
    (property "Val" "100n")
    (property "Voltage" "")
    (property "ki_description" " ")
    (attr smd)
    (fp_text reference "C276" (at 1.37 1.08 180) (layer "B.SilkS")
        (effects (font (size 0.7 0.7) (thickness 0.15)) (justify left bottom mirror))
    )
    (fp_text value "C_100n_0201" (at 0 -1.4 180) (layer "B.Fab") hide
        (effects (font (size 0.7 0.7) (thickness 0.15)) (justify left bottom mirror))
    )
    (fp_text user "License: Apache-2.0" (at -0.72 -4.4 180) (layer "B.Fab") hide
        (effects (font (size 0.7 0.7) (thickness 0.15)) (justify left bottom mirror))
    )
    (fp_text user "Author: Antmicro" (at -0.72 -5.4 180) (layer "B.Fab") hide
        (effects (font (size 0.7 0.7) (thickness 0.15)) (justify left bottom mirror))
    )
    (fp_text user "${REFERENCE}" (at -0.72 -3.4 180) (layer "B.Fab") hide
        (effects (font (size 0.7 0.7) (thickness 0.15)) (justify left bottom mirror))
    )
    (fp_rect (start -0.72 0.38) (end 0.72 -0.38)
      (stroke (width 0.05) (type solid)) (fill none) (layer "B.CrtYd"))
    (fp_rect (start 0.3 -0.15) (end -0.301 0.149)
      (stroke (width 0.15) (type solid)) (fill none) (layer "B.Fab"))
    (pad "" smd roundrect (at -0.349 0.002) (size 0.318 0.36) (layers "B.Paste") (roundrect_rratio 0.25))
    (pad "" smd roundrect (at 0.341 0.002) (size 0.318 0.36) (layers "B.Paste") (roundrect_rratio 0.25))
    (pad "1" smd roundrect (at -0.321 0.002) (size 0.46 0.4) (layers "B.Cu" "B.Mask") (roundrect_rratio 0.25)
      (net 77 "VDDQ") (pintype "passive"))
    (pad "2" smd roundrect (at 0.32 0.002) (size 0.46 0.4) (layers "B.Cu" "B.Mask") (roundrect_rratio 0.25)
      (net 9 "GND") (pintype "passive"))
  )
)
